# T6G (Grand Teton) — schematic netlist excerpt (pin names and nets, part order shuffled) for the footprints in the layout excerpt that follows; sources: Cadence DE-HDL packaged netlist, KiCad conversion of 04192023_DAF0TMB3IC0_F0TG_MB_C_brd_V02_OCP.brd

R1323  Q_RES  0.002 1% CHIP  pkg 2512LF  page 357 : A = P12V_E1S_0_R ; B = P12V_E1S_0
C888  Q_CAP_DIFFBUS  DIFF BUS_0.22UF 6.3V 20% X6S  pkg C0201  page 64 : \1\ = P5E_CPU0_P3_TX_C_DN<6> ; \2\ = P5E_CPU0_P3_TX_DN<6>
C6712  Q_CAP_DIFFBUS  DIFF BUS_0.22UF 6.3V 20% X6S  pkg C0201  page 341 : \1\ = P5E_CPU1_P2_TX_BUF_C_DN<9> ; \2\ = P5E_CPU1_P2_TX_BUF_DN<9>
PR6619  Q_RES  0 5% CHIP  pkg 0402LF  page 365 : A = P5V_AUX ; B = P0V9_RETIMER_CPU1_PVCC

(kicad_pcb
	(version 20260206)
	(generator "pcbnew")
	(generator_version "10.0")
	(general
		(thickness 1.6)
		(legacy_teardrops no)
	)
	(paper "A4")
	(title_block
		(title "04192023_DAF0TMB3IC0_F0TG_MB_C_brd_V02_OCP.brd")
		(comment 1 "Grand Teton / footprints 4543-4546 of 8354")
	)
	(layers
		(0 "F.Cu" signal "TOP")
		(4 "In1.Cu" signal "GND")
		(6 "In2.Cu" signal "IN1")
		(8 "In3.Cu" signal "GND1")
		(10 "In4.Cu" signal "IN2")
		(12 "In5.Cu" signal "GND2")
		(14 "In6.Cu" signal "IN3")
		(16 "In7.Cu" signal "GND3")
		(18 "In8.Cu" signal "VCC")
		(20 "In9.Cu" signal "VCC1")
		(22 "In10.Cu" signal "GND4")
		(24 "In11.Cu" signal "IN4")
		(26 "In12.Cu" signal "GND5")
		(28 "In13.Cu" signal "IN5")
		(30 "In14.Cu" signal "GND6")
		(32 "In15.Cu" signal "IN6")
		(34 "In16.Cu" signal "GND7")
		(2 "B.Cu" signal "BOTTOM")
		(9 "F.Adhes" user "F.Adhesive")
		(11 "B.Adhes" user "B.Adhesive")
		(13 "F.Paste" user "Package Geometry/Pastemask Top")
		(15 "B.Paste" user "Package Geometry/Pastemask Bottom")
		(5 "F.SilkS" user "Ref Des/Silkscreen Top")
		(7 "B.SilkS" user "Ref Des/Silkscreen Bottom")
		(1 "F.Mask" user "Board Geometry/Soldermask Top")
		(3 "B.Mask" user "Board Geometry/Soldermask Bottom")
		(17 "Dwgs.User" user "User.Drawings")
		(19 "Cmts.User" user "User.Comments")
		(21 "Eco1.User" user "User.Eco1")
		(23 "Eco2.User" user "User.Eco2")
		(25 "Edge.Cuts" user "Board Geometry/Outline")
		(27 "Margin" user)
		(31 "F.CrtYd" user "Package Geometry/Place Bound Top")
		(29 "B.CrtYd" user "Package Geometry/Place Bound Bottom")
		(35 "F.Fab" user "Ref Des/Assembly Top")
		(33 "B.Fab" user "Ref Des/Assembly Bottom")
	)
	(footprint ""
		(layer "F.Cu")
		(at 142.437866 -408.517344 -90)
		(property "Reference" "C6712"
			(at 0 0 270)
			(layer "F.SilkS")
			(hide yes)
			(effects
				(font
					(size 1.27 1.27)
				)
			)
		)
		(property "Value" ""
			(at 0 0 270)
			(layer "F.Fab")
			(effects
				(font
					(size 1.27 1.27)
				)
			)
		)
		(duplicate_pad_numbers_are_jumpers no)
		(fp_line
			(start -0.299974 0.150114)
			(end -0.299974 -0.150114)
			(stroke
				(width 0.1)
				(type default)
			)
			(layer "F.Fab")
		)
		(fp_line
			(start 0.299974 0.150114)
			(end -0.299974 0.150114)
			(stroke
				(width 0.1)
				(type default)
			)
			(layer "F.Fab")
		)
		(fp_line
			(start -0.299974 -0.150114)
			(end 0.299974 -0.150114)
			(stroke
				(width 0.1)
				(type default)
			)
			(layer "F.Fab")
		)
		(fp_line
			(start 0.299974 -0.150114)
			(end 0.299974 0.150114)
			(stroke
				(width 0.1)
				(type default)
			)
			(layer "F.Fab")
		)
		(pad "1" smd rect
			(at -0.2667 0 270)
			(size 0.3048 0.381)
			(layers "F.Cu" "F.Mask" "F.Paste")
			(net "P5E_CPU1_P2_TX_BUF_C_DN<9>")
		)
		(pad "2" smd rect
			(at 0.2667 0 270)
			(size 0.3048 0.381)
			(layers "F.Cu" "F.Mask" "F.Paste")
			(net "P5E_CPU1_P2_TX_BUF_DN<9>")
		)
	)
	(footprint ""
		(layer "F.Cu")
		(at 11.7221 -394.22832 -90)
		(property "Reference" "PR6619"
			(at 0 0 270)
			(layer "F.SilkS")
			(hide yes)
			(effects
				(font
					(size 1.27 1.27)
				)
			)
		)
		(property "Value" ""
			(at 0 0 270)
			(layer "F.Fab")
			(effects
				(font
					(size 1.27 1.27)
				)
			)
		)
		(duplicate_pad_numbers_are_jumpers no)
		(fp_line
			(start -0.7874 0.4064)
			(end -0.7874 -0.4064)
			(stroke
				(width 0.1524)
				(type default)
			)
			(layer "F.SilkS")
		)
		(fp_line
			(start 0.7874 0.4064)
			(end -0.7874 0.4064)
			(stroke
				(width 0.1524)
				(type default)
			)
			(layer "F.SilkS")
		)
		(fp_line
			(start -0.7874 -0.4064)
			(end 0.7874 -0.4064)
			(stroke
				(width 0.1524)
				(type default)
			)
			(layer "F.SilkS")
		)
		(fp_line
			(start 0.7874 -0.4064)
			(end 0.7874 0.4064)
			(stroke
				(width 0.1524)
				(type default)
			)
			(layer "F.SilkS")
		)
		(fp_line
			(start -0.67945 0.3048)
			(end -0.67945 -0.305054)
			(stroke
				(width 0.1)
				(type default)
			)
			(layer "F.Fab")
		)
		(fp_line
			(start -0.12065 0.3048)
			(end -0.67945 0.3048)
			(stroke
				(width 0.1)
				(type default)
			)
			(layer "F.Fab")
		)
		(fp_line
			(start 0.120396 0.3048)
			(end 0.120396 0.2794)
			(stroke
				(width 0.1)
				(type default)
			)
			(layer "F.Fab")
		)
		(fp_line
			(start 0.67945 0.3048)
			(end 0.120396 0.3048)
			(stroke
				(width 0.1)
				(type default)
			)
			(layer "F.Fab")
		)
		(fp_line
			(start -0.12065 0.2794)
			(end -0.12065 0.3048)
			(stroke
				(width 0.1)
				(type default)
			)
			(layer "F.Fab")
		)
		(fp_line
			(start 0.120396 0.2794)
			(end -0.12065 0.2794)
			(stroke
				(width 0.1)
				(type default)
			)
			(layer "F.Fab")
		)
		(fp_line
			(start -0.12065 -0.2794)
			(end 0.12065 -0.2794)
			(stroke
				(width 0.1)
				(type default)
			)
			(layer "F.Fab")
		)
		(fp_line
			(start 0.12065 -0.2794)
			(end 0.12065 -0.3048)
			(stroke
				(width 0.1)
				(type default)
			)
			(layer "F.Fab")
		)
		(fp_line
			(start 0.12065 -0.3048)
			(end 0.67945 -0.3048)
			(stroke
				(width 0.1)
				(type default)
			)
			(layer "F.Fab")
		)
		(fp_line
			(start 0.67945 -0.3048)
			(end 0.67945 0.3048)
			(stroke
				(width 0.1)
				(type default)
			)
			(layer "F.Fab")
		)
		(fp_line
			(start -0.67945 -0.305054)
			(end -0.12065 -0.305054)
			(stroke
				(width 0.1)
				(type default)
			)
			(layer "F.Fab")
		)
		(fp_line
			(start -0.12065 -0.305054)
			(end -0.12065 -0.2794)
			(stroke
				(width 0.1)
				(type default)
			)
			(layer "F.Fab")
		)
		(pad "1" smd circle
			(at -0.40005 0 270)
			(size 0 0)
			(layers "F.Cu" "F.Mask" "F.Paste")
			(net "P5V_AUX")
		)
		(pad "2" smd circle
			(at 0.40005 0 270)
			(size 0 0)
			(layers "F.Cu" "F.Mask" "F.Paste")
			(net "P0V9_RETIMER_CPU1_PVCC")
		)
	)
	(footprint ""
		(layer "F.Cu")
		(at 375.513092 -378.95403 -90)
		(property "Reference" "C888"
			(at 0 0 270)
			(layer "F.SilkS")
			(hide yes)
			(effects
				(font
					(size 1.27 1.27)
				)
			)
		)
		(property "Value" ""
			(at 0 0 270)
			(layer "F.Fab")
			(effects
				(font
					(size 1.27 1.27)
				)
			)
		)
		(duplicate_pad_numbers_are_jumpers no)
		(fp_line
			(start -0.299974 0.150114)
			(end -0.299974 -0.150114)
			(stroke
				(width 0.1)
				(type default)
			)
			(layer "F.Fab")
		)
		(fp_line
			(start 0.299974 0.150114)
			(end -0.299974 0.150114)
			(stroke
				(width 0.1)
				(type default)
			)
			(layer "F.Fab")
		)
		(fp_line
			(start -0.299974 -0.150114)
			(end 0.299974 -0.150114)
			(stroke
				(width 0.1)
				(type default)
			)
			(layer "F.Fab")
		)
		(fp_line
			(start 0.299974 -0.150114)
			(end 0.299974 0.150114)
			(stroke
				(width 0.1)
				(type default)
			)
			(layer "F.Fab")
		)
		(pad "1" smd rect
			(at -0.2667 0 270)
			(size 0.3048 0.381)
			(layers "F.Cu" "F.Mask" "F.Paste")
			(net "P5E_CPU0_P3_TX_C_DN<6>")
		)
		(pad "2" smd rect
			(at 0.2667 0 270)
			(size 0.3048 0.381)
			(layers "F.Cu" "F.Mask" "F.Paste")
			(net "P5E_CPU0_P3_TX_DN<6>")
		)
	)
	(footprint ""
		(layer "F.Cu")
		(at 244.58803 -47.719234)
		(property "Reference" "R1323"
			(at 1.28397 -3.816096 0)
			(unlocked yes)
			(layer "F.SilkS")
			(effects
				(font
					(size 0.7874 0.5842)
					(thickness 0.1524)
				)
				(justify left)
			)
		)
		(property "Value" ""
			(at 0 0 0)
			(layer "F.Fab")
			(effects
				(font
					(size 1.27 1.27)
				)
			)
		)
		(duplicate_pad_numbers_are_jumpers no)
		(fp_line
			(start -3.937508 -1.8796)
			(end -3.937508 1.8796)
			(stroke
				(width 0.1524)
				(type default)
			)
			(layer "F.SilkS")
		)
		(fp_line
			(start -3.937508 1.8796)
			(end 3.937508 1.8796)
			(stroke
				(width 0.1524)
				(type default)
			)
			(layer "F.SilkS")
		)
		(fp_line
			(start 3.937508 -1.8796)
			(end -3.937508 -1.8796)
			(stroke
				(width 0.1524)
				(type default)
			)
			(layer "F.SilkS")
		)
		(fp_line
			(start 3.937508 1.8796)
			(end 3.937508 -1.8796)
			(stroke
				(width 0.1524)
				(type default)
			)
			(layer "F.SilkS")
		)
		(fp_line
			(start -3.275076 -1.674876)
			(end -3.275076 1.674876)
			(stroke
				(width 0.1)
				(type default)
			)
			(layer "F.Fab")
		)
		(fp_line
			(start -3.275076 1.674876)
			(end 3.275076 1.674876)
			(stroke
				(width 0.1)
				(type default)
			)
			(layer "F.Fab")
		)
		(fp_line
			(start 3.275076 -1.674876)
			(end -3.275076 -1.674876)
			(stroke
				(width 0.1)
				(type default)
			)
			(layer "F.Fab")
		)
		(fp_line
			(start 3.275076 1.674876)
			(end 3.275076 -1.674876)
			(stroke
				(width 0.1)
				(type default)
			)
			(layer "F.Fab")
		)
		(pad "1" smd rect
			(at -2.350008 0)
			(size 2.921 3.5052)
			(layers "F.Cu" "F.Mask" "F.Paste")
			(net "P12V_E1S_0_R")
		)
		(pad "2" smd rect
			(at 2.350008 0)
			(size 2.921 3.5052)
			(layers "F.Cu" "F.Mask" "F.Paste")
			(net "P12V_E1S_0")
		)
	)
)
